M48
INCH,TZ
T01C.008
T02C.01
T03C.012
T04C.014
T05C.01417
T06C.016
T07C.028
T08C.032
T09C.034
T010C.035
T011C.04
T012C.044
T013C.048
T014C.063
T015C.086
T016C.094
T017C.097
T018C.126
T019C.13
T020C.134
T021C.138
T022C.158
T023C.168
;EXTENTS: -105.600 -111.400 128.200 113.400 
;LEADER: 12 
;HEADER: 
;CODE  : ASCII 
;FILE  : 16342-2.rou for board 16342-2.brd
%
G90
F1
M16
T020
M16
G00X302552Y413583
G40
M15
G01X315952
M16
G00X83064Y238386
G40
M15
G01X96464
M16
T08
M16
G00X339331Y90729
G40
M15
G01Y93129
M16
G00X360669Y48602
G40
M15
G01Y51002
M16
G00X339331Y47252
G40
M15
G01Y52352
M16
G00X360669Y89379
G40
M15
G01Y94479
M16
T018
M16
G00X804724Y80511
G40
M15
G01Y86811
M16
G00Y198622
G40
M15
G01Y204922
M16
G00X706299Y80511
G40
M15
G01Y86811
M16
G00Y198621
G40
M15
G01Y204921
M16
G40
M30
